(kicad_pcb
	(version 20241229)
	(generator "pcbnew")
	(generator_version "9.0")
	(general
		(thickness 1.711)
		(legacy_teardrops no)
	)
	(paper "A4")
	(title_block
		(title "Antmicro Baseboard for Jetson AGX Thor")
		(date "2026-02-18")
		(rev "1.1.0")
		(company "Antmicro Ltd")
		(comment 1 "www.antmicro.com")
		(comment 9 "footprints 852-856 of 1170")
	)
	(layers
		(0 "F.Cu" signal)
		(4 "In1.Cu" signal)
		(6 "In2.Cu" signal)
		(8 "In3.Cu" signal)
		(10 "In4.Cu" jumper)
		(12 "In5.Cu" signal)
		(14 "In6.Cu" signal)
		(16 "In7.Cu" signal)
		(18 "In8.Cu" signal)
		(2 "B.Cu" signal)
		(9 "F.Adhes" user "F.Adhesive")
		(11 "B.Adhes" user "B.Adhesive")
		(13 "F.Paste" user)
		(15 "B.Paste" user)
		(5 "F.SilkS" user "F.Silkscreen")
		(7 "B.SilkS" user "B.Silkscreen")
		(1 "F.Mask" user)
		(3 "B.Mask" user)
		(17 "Dwgs.User" user "User.Drawings")
		(19 "Cmts.User" user "User.Comments")
		(21 "Eco1.User" user "User.Eco1")
		(23 "Eco2.User" user "User.Eco2")
		(25 "Edge.Cuts" user)
		(27 "Margin" user)
		(31 "F.CrtYd" user "F.Courtyard")
		(29 "B.CrtYd" user "B.Courtyard")
		(35 "F.Fab" user)
		(33 "B.Fab" user)
	)
	(footprint "antmicro-footprints:C_0603_1608Metric_EIA"
		(layer "B.Cu")
		(at 118.130532 69.46)
		(descr "Capacitor SMD 0603, IPC-7351 Density Level A")
		(tags "Capacitor 0603")
		(property "Reference" "C21"
			(at 0.969468 -0.86 180)
			(layer "B.SilkS")
			(effects
				(font
					(size 0.7 0.7)
					(thickness 0.15)
				)
				(justify left bottom mirror)
			)
		)
		(property "Value" "C_22u_16V_0603"
			(at -1.42757 -1.770288 180)
			(layer "B.Fab")
			(effects
				(font
					(size 0.7 0.7)
					(thickness 0.15)
				)
				(justify left bottom mirror)
			)
		)
		(property "Datasheet" "https://product.samsungsem.com/mlcc/CL10A226MO7JZN.do"
			(at 0 0 180)
			(layer "B.Fab")
			(hide yes)
			(effects
				(font
					(size 1.27 1.27)
					(thickness 0.15)
				)
				(justify mirror)
			)
		)
		(property "Description" "SMD Multilayer Ceramic Capacitor"
			(at 0 0 180)
			(layer "B.Fab")
			(hide yes)
			(effects
				(font
					(size 1.27 1.27)
					(thickness 0.15)
				)
				(justify mirror)
			)
		)
		(property "MPN" "CL10A226MO7JZNC"
			(at 0 0 0)
			(unlocked yes)
			(layer "B.Fab")
			(hide yes)
			(effects
				(font
					(size 1 1)
					(thickness 0.15)
				)
				(justify mirror)
			)
		)
		(property "Manufacturer" "Samsung Electro-Mechanics"
			(at 0 0 0)
			(unlocked yes)
			(layer "B.Fab")
			(hide yes)
			(effects
				(font
					(size 1 1)
					(thickness 0.15)
				)
				(justify mirror)
			)
		)
		(property "License" "Apache-2.0"
			(at 0 0 0)
			(unlocked yes)
			(layer "B.Fab")
			(hide yes)
			(effects
				(font
					(size 1 1)
					(thickness 0.15)
				)
				(justify mirror)
			)
		)
		(property "Author" "Antmicro"
			(at 0 0 0)
			(unlocked yes)
			(layer "B.Fab")
			(hide yes)
			(effects
				(font
					(size 1 1)
					(thickness 0.15)
				)
				(justify mirror)
			)
		)
		(property "Val" "22u"
			(at 0 0 0)
			(unlocked yes)
			(layer "B.Fab")
			(hide yes)
			(effects
				(font
					(size 1 1)
					(thickness 0.15)
				)
				(justify mirror)
			)
		)
		(property "Voltage" "16V"
			(at 0 0 0)
			(unlocked yes)
			(layer "B.Fab")
			(hide yes)
			(effects
				(font
					(size 1 1)
					(thickness 0.15)
				)
				(justify mirror)
			)
		)
		(property "Dielectric" "X7R"
			(at 0 0 0)
			(unlocked yes)
			(layer "B.Fab")
			(hide yes)
			(effects
				(font
					(size 1 1)
					(thickness 0.15)
				)
				(justify mirror)
			)
		)
		(property "Public" "False"
			(at 0 0 0)
			(unlocked yes)
			(layer "B.Fab")
			(hide yes)
			(effects
				(font
					(size 1 1)
					(thickness 0.15)
				)
				(justify mirror)
			)
		)
		(sheetname "/SoM_Power/")
		(sheetfile "som_power.kicad_sch")
		(attr smd)
		(fp_line
			(start -0.15 -0.55)
			(end 0.15 -0.55)
			(stroke
				(width 0.15)
				(type solid)
			)
			(layer "B.SilkS")
		)
		(fp_line
			(start -0.15 0.55)
			(end 0.15 0.55)
			(stroke
				(width 0.15)
				(type solid)
			)
			(layer "B.SilkS")
		)
		(fp_rect
			(start -1.25 0.65)
			(end 1.25 -0.65)
			(stroke
				(width 0.05)
				(type solid)
			)
			(fill no)
			(layer "B.CrtYd")
		)
		(fp_rect
			(start -0.8 0.45)
			(end 0.8 -0.45)
			(stroke
				(width 0.15)
				(type solid)
			)
			(fill no)
			(layer "B.Fab")
		)
		(fp_text user "${REFERENCE}"
			(at -1.682 -3.895 180)
			(layer "B.Fab")
			(effects
				(font
					(size 0.7 0.7)
					(thickness 0.15)
				)
				(justify left bottom mirror)
			)
		)
		(fp_text user "Author: Antmicro"
			(at -1.682 -4.894 180)
			(layer "B.Fab")
			(effects
				(font
					(size 0.7 0.7)
					(thickness 0.15)
				)
				(justify left bottom mirror)
			)
		)
		(fp_text user "License: Apache-2.0"
			(at -1.682 -5.895 180)
			(layer "B.Fab")
			(effects
				(font
					(size 0.7 0.7)
					(thickness 0.15)
				)
				(justify left bottom mirror)
			)
		)
		(pad "1" smd roundrect
			(at -0.7 0)
			(size 0.8 1.1)
			(layers "B.Cu" "B.Mask" "B.Paste")
			(roundrect_rratio 0.2)
			(net 1 "GND")
			(pintype "passive")
		)
		(pad "2" smd roundrect
			(at 0.7 0)
			(size 0.8 1.1)
			(layers "B.Cu" "B.Mask" "B.Paste")
			(roundrect_rratio 0.2)
			(net 213 "+5V_SOM")
			(pintype "passive")
		)
	)
	(footprint "antmicro-footprints:SOT-563"
		(layer "B.Cu")
		(at 220.18 111.27 90)
		(property "Reference" "Q21"
			(at -1.33 1.32 90)
			(layer "B.SilkS")
			(effects
				(font
					(size 0.7 0.7)
					(thickness 0.15)
				)
				(justify right top mirror)
			)
		)
		(property "Value" "DMC2400UV-7"
			(at 0 -2 90)
			(layer "B.Fab")
			(effects
				(font
					(size 0.7 0.7)
					(thickness 0.15)
				)
				(justify right top mirror)
			)
		)
		(property "Datasheet" "https://www.mouser.com/datasheet/2/115/DIOD_S_A0010038249_1-2543538.pdf"
			(at 0 0 90)
			(layer "B.Fab")
			(hide yes)
			(effects
				(font
					(size 1.27 1.27)
					(thickness 0.15)
				)
				(justify mirror)
			)
		)
		(property "Description" "Dual MOSFET, Complementary N and P Channel, 20 V, 20 V, 1.03 A, 1.03 A, 0.3 ohm"
			(at 0 0 90)
			(layer "B.Fab")
			(hide yes)
			(effects
				(font
					(size 1.27 1.27)
					(thickness 0.15)
				)
				(justify mirror)
			)
		)
		(property "MPN" "DMC2400UV-7"
			(at 0 0 270)
			(unlocked yes)
			(layer "B.Fab")
			(hide yes)
			(effects
				(font
					(size 1 1)
					(thickness 0.15)
				)
				(justify mirror)
			)
		)
		(property "Manufacturer" "Diodes Incorporated"
			(at 0 0 270)
			(unlocked yes)
			(layer "B.Fab")
			(hide yes)
			(effects
				(font
					(size 1 1)
					(thickness 0.15)
				)
				(justify mirror)
			)
		)
		(property "Author" "Antmicro"
			(at 0 0 270)
			(unlocked yes)
			(layer "B.Fab")
			(hide yes)
			(effects
				(font
					(size 1 1)
					(thickness 0.15)
				)
				(justify mirror)
			)
		)
		(property "License" "Apache-2.0"
			(at 0 0 270)
			(unlocked yes)
			(layer "B.Fab")
			(hide yes)
			(effects
				(font
					(size 1 1)
					(thickness 0.15)
				)
				(justify mirror)
			)
		)
		(sheetname "/USB Hub/")
		(sheetfile "usb_hub.kicad_sch")
		(attr smd)
		(fp_line
			(start 0.776 -0.972)
			(end 0.526 -0.972)
			(stroke
				(width 0.15)
				(type solid)
			)
			(layer "B.SilkS")
		)
		(fp_line
			(start -0.778 -0.949)
			(end -0.424 -0.949)
			(stroke
				(width 0.15)
				(type solid)
			)
			(layer "B.SilkS")
		)
		(fp_line
			(start 0.776 -0.776)
			(end 0.776 -0.972)
			(stroke
				(width 0.15)
				(type solid)
			)
			(layer "B.SilkS")
		)
		(fp_line
			(start -0.778 -0.776)
			(end -0.778 -0.949)
			(stroke
				(width 0.15)
				(type solid)
			)
			(layer "B.SilkS")
		)
		(fp_line
			(start 0.776 0.974)
			(end 0.776 0.778)
			(stroke
				(width 0.15)
				(type solid)
			)
			(layer "B.SilkS")
		)
		(fp_line
			(start 0.776 0.974)
			(end 0.526 0.974)
			(stroke
				(width 0.15)
				(type solid)
			)
			(layer "B.SilkS")
		)
		(fp_line
			(start -0.499 0.974)
			(end -0.724 0.778)
			(stroke
				(width 0.15)
				(type solid)
			)
			(layer "B.SilkS")
		)
		(fp_circle
			(center -0.903 0.999)
			(end -0.952 0.95)
			(stroke
				(width 0.15)
				(type solid)
			)
			(fill yes)
			(layer "B.SilkS")
		)
		(fp_rect
			(start 1.19 1.12)
			(end -1.2 -1.1)
			(stroke
				(width 0.05)
				(type solid)
			)
			(fill no)
			(layer "B.CrtYd")
		)
		(fp_line
			(start 0.651 -0.847)
			(end -0.653 -0.847)
			(stroke
				(width 0.15)
				(type solid)
			)
			(layer "B.Fab")
		)
		(fp_line
			(start -0.653 0.678)
			(end -0.653 -0.847)
			(stroke
				(width 0.15)
				(type solid)
			)
			(layer "B.Fab")
		)
		(fp_line
			(start 0.651 0.849)
			(end 0.651 -0.847)
			(stroke
				(width 0.15)
				(type solid)
			)
			(layer "B.Fab")
		)
		(fp_line
			(start -0.453 0.849)
			(end -0.653 0.678)
			(stroke
				(width 0.15)
				(type solid)
			)
			(layer "B.Fab")
		)
		(fp_line
			(start -0.453 0.849)
			(end 0.651 0.849)
			(stroke
				(width 0.15)
				(type solid)
			)
			(layer "B.Fab")
		)
		(fp_text user "${REFERENCE}"
			(at -1.299 -7.323 90)
			(layer "B.Fab")
			(effects
				(font
					(size 0.7 0.7)
					(thickness 0.15)
				)
				(justify right top mirror)
			)
		)
		(fp_text user "Author: Antmicro"
			(at -1.299 -6.124 90)
			(layer "B.Fab")
			(effects
				(font
					(size 0.7 0.7)
					(thickness 0.15)
				)
				(justify right top mirror)
			)
		)
		(fp_text user "License: Apache-2.0"
			(at -1.299 -4.924 90)
			(layer "B.Fab")
			(effects
				(font
					(size 0.7 0.7)
					(thickness 0.15)
				)
				(justify right top mirror)
			)
		)
		(pad "1" smd roundrect
			(at -0.749 0.499 180)
			(size 0.3 0.6)
			(layers "B.Cu" "B.Mask" "B.Paste")
			(roundrect_rratio 0.25)
			(net 1 "GND")
			(pinfunction "S1")
			(pintype "passive")
		)
		(pad "2" smd roundrect
			(at -0.749 -0.001 180)
			(size 0.3 0.6)
			(layers "B.Cu" "B.Mask" "B.Paste")
			(roundrect_rratio 0.25)
			(net 1099 "/USB Hub/DP2_VCONN1")
			(pinfunction "G1")
			(pintype "input")
		)
		(pad "3" smd roundrect
			(at -0.749 -0.497 180)
			(size 0.3 0.6)
			(layers "B.Cu" "B.Mask" "B.Paste")
			(roundrect_rratio 0.25)
			(net 1019 "Net-(D57-A)")
			(pinfunction "D2")
			(pintype "passive")
		)
		(pad "4" smd roundrect
			(at 0.747 -0.497 180)
			(size 0.3 0.6)
			(layers "B.Cu" "B.Mask" "B.Paste")
			(roundrect_rratio 0.25)
			(net 5 "+5V")
			(pinfunction "S2")
			(pintype "passive")
		)
		(pad "5" smd roundrect
			(at 0.747 -0.001 180)
			(size 0.3 0.6)
			(layers "B.Cu" "B.Mask" "B.Paste")
			(roundrect_rratio 0.25)
			(net 1330 "Net-(Q21-D1)")
			(pinfunction "G2")
			(pintype "input")
		)
		(pad "6" smd roundrect
			(at 0.747 0.499 180)
			(size 0.3 0.6)
			(layers "B.Cu" "B.Mask" "B.Paste")
			(roundrect_rratio 0.25)
			(net 1330 "Net-(Q21-D1)")
			(pinfunction "D1")
			(pintype "passive")
		)
	)
	(footprint "antmicro-footprints:R_0402_1005Metric"
		(layer "B.Cu")
		(at 216 90.22 180)
		(descr "Resistor SMD 0402")
		(tags "resistor SMD 0402")
		(property "Reference" "R140"
			(at -7.6 -2.28 0)
			(layer "B.SilkS")
			(effects
				(font
					(size 0.7 0.7)
					(thickness 0.15)
				)
				(justify left bottom mirror)
			)
		)
		(property "Value" "R_1k_0402"
			(at -1.011843 -1.772047 0)
			(layer "B.Fab")
			(effects
				(font
					(size 0.7 0.7)
					(thickness 0.15)
				)
				(justify left bottom mirror)
			)
		)
		(property "Datasheet" "https://www.bourns.com/docs/product-datasheets/cr.pdf"
			(at 0 0 0)
			(layer "B.Fab")
			(hide yes)
			(effects
				(font
					(size 1.27 1.27)
					(thickness 0.15)
				)
				(justify mirror)
			)
		)
		(property "Description" "SMD Chip Resistor, 1 kohm, ± 1%, 63 mW, 0402 [1005 Metric], Thick Film, General Purpose"
			(at 0 0 0)
			(layer "B.Fab")
			(hide yes)
			(effects
				(font
					(size 1.27 1.27)
					(thickness 0.15)
				)
				(justify mirror)
			)
		)
		(property "Manufacturer" "Bourns"
			(at 0 0 0)
			(unlocked yes)
			(layer "B.Fab")
			(hide yes)
			(effects
				(font
					(size 1 1)
					(thickness 0.15)
				)
				(justify mirror)
			)
		)
		(property "MPN" "CR0402-FX-1001GLF"
			(at 0 0 0)
			(unlocked yes)
			(layer "B.Fab")
			(hide yes)
			(effects
				(font
					(size 1 1)
					(thickness 0.15)
				)
				(justify mirror)
			)
		)
		(property "Val" "1k"
			(at 0 0 0)
			(unlocked yes)
			(layer "B.Fab")
			(hide yes)
			(effects
				(font
					(size 1 1)
					(thickness 0.15)
				)
				(justify mirror)
			)
		)
		(property "License" "Apache-2.0"
			(at 0 0 0)
			(unlocked yes)
			(layer "B.Fab")
			(hide yes)
			(effects
				(font
					(size 1 1)
					(thickness 0.15)
				)
				(justify mirror)
			)
		)
		(property "Author" "Antmicro"
			(at 0 0 0)
			(unlocked yes)
			(layer "B.Fab")
			(hide yes)
			(effects
				(font
					(size 1 1)
					(thickness 0.15)
				)
				(justify mirror)
			)
		)
		(property "Tolerance" "1%"
			(at 0 0 0)
			(unlocked yes)
			(layer "B.Fab")
			(hide yes)
			(effects
				(font
					(size 1 1)
					(thickness 0.15)
				)
				(justify mirror)
			)
		)
		(sheetname "/USB DP Alt mode/")
		(sheetfile "usb_dp.kicad_sch")
		(attr smd exclude_from_pos_files exclude_from_bom dnp)
		(fp_rect
			(start -0.925 0.47)
			(end 0.925 -0.47)
			(stroke
				(width 0.05)
				(type default)
			)
			(fill no)
			(layer "B.CrtYd")
		)
		(fp_rect
			(start -0.5 0.25)
			(end 0.5 -0.25)
			(stroke
				(width 0.15)
				(type solid)
			)
			(fill no)
			(layer "B.Fab")
		)
		(fp_text user "License: Apache-2.0"
			(at -0.95 -5.169 0)
			(layer "B.Fab")
			(effects
				(font
					(size 0.7 0.7)
					(thickness 0.15)
				)
				(justify left bottom mirror)
			)
		)
		(fp_text user "Author: Antmicro"
			(at -0.95 -4.169 0)
			(layer "B.Fab")
			(effects
				(font
					(size 0.7 0.7)
					(thickness 0.15)
				)
				(justify left bottom mirror)
			)
		)
		(fp_text user "${REFERENCE}"
			(at -0.95 -3.168 0)
			(layer "B.Fab")
			(effects
				(font
					(size 0.7 0.7)
					(thickness 0.15)
				)
				(justify left bottom mirror)
			)
		)
		(pad "1" smd roundrect
			(at -0.48 0 180)
			(size 0.59 0.64)
			(layers "B.Cu" "B.Mask" "B.Paste")
			(roundrect_rratio 0.25)
			(net 969 "/USB DP Alt mode/USBC1_EQ1")
			(pintype "passive")
		)
		(pad "2" smd roundrect
			(at 0.48 0 180)
			(size 0.59 0.64)
			(layers "B.Cu" "B.Mask" "B.Paste")
			(roundrect_rratio 0.25)
			(net 2 "+3V3")
			(pintype "passive")
		)
	)
	(footprint "antmicro-footprints:R_0402_1005Metric"
		(layer "B.Cu")
		(at 63.2 66.5 -90)
		(descr "Resistor SMD 0402")
		(tags "resistor SMD 0402")
		(property "Reference" "R164"
			(at -9.7 0 90)
			(layer "B.SilkS")
			(effects
				(font
					(size 0.7 0.7)
					(thickness 0.15)
				)
				(justify left bottom mirror)
			)
		)
		(property "Value" "R_2k2_0402"
			(at -1.011843 -1.772047 90)
			(layer "B.Fab")
			(effects
				(font
					(size 0.7 0.7)
					(thickness 0.15)
				)
				(justify left bottom mirror)
			)
		)
		(property "Datasheet" "https://www.bourns.com/docs/product-datasheets/cr.pdf"
			(at 0 0 90)
			(layer "B.Fab")
			(hide yes)
			(effects
				(font
					(size 1.27 1.27)
					(thickness 0.15)
				)
				(justify mirror)
			)
		)
		(property "Description" "SMD Chip Resistor, 2.2 kohm, ± 1%, 62.5 mW, 0402 [1005 Metric], Thick Film, General Purpose"
			(at 0 0 90)
			(layer "B.Fab")
			(hide yes)
			(effects
				(font
					(size 1.27 1.27)
					(thickness 0.15)
				)
				(justify mirror)
			)
		)
		(property "MPN" "CR0402-FX-2201GLF"
			(at 0 0 90)
			(unlocked yes)
			(layer "B.Fab")
			(hide yes)
			(effects
				(font
					(size 1 1)
					(thickness 0.15)
				)
				(justify mirror)
			)
		)
		(property "Manufacturer" "Bourns"
			(at 0 0 90)
			(unlocked yes)
			(layer "B.Fab")
			(hide yes)
			(effects
				(font
					(size 1 1)
					(thickness 0.15)
				)
				(justify mirror)
			)
		)
		(property "License" "Apache-2.0"
			(at 0 0 90)
			(unlocked yes)
			(layer "B.Fab")
			(hide yes)
			(effects
				(font
					(size 1 1)
					(thickness 0.15)
				)
				(justify mirror)
			)
		)
		(property "Author" "Antmicro"
			(at 0 0 90)
			(unlocked yes)
			(layer "B.Fab")
			(hide yes)
			(effects
				(font
					(size 1 1)
					(thickness 0.15)
				)
				(justify mirror)
			)
		)
		(property "Val" "2k2"
			(at 0 0 90)
			(unlocked yes)
			(layer "B.Fab")
			(hide yes)
			(effects
				(font
					(size 1 1)
					(thickness 0.15)
				)
				(justify mirror)
			)
		)
		(property "Tolerance" "1%"
			(at 0 0 90)
			(unlocked yes)
			(layer "B.Fab")
			(hide yes)
			(effects
				(font
					(size 1 1)
					(thickness 0.15)
				)
				(justify mirror)
			)
		)
		(sheetname "/CSI/")
		(sheetfile "csi.kicad_sch")
		(attr smd)
		(fp_rect
			(start -0.925 0.47)
			(end 0.925 -0.47)
			(stroke
				(width 0.05)
				(type default)
			)
			(fill no)
			(layer "B.CrtYd")
		)
		(fp_rect
			(start -0.5 0.25)
			(end 0.5 -0.25)
			(stroke
				(width 0.15)
				(type solid)
			)
			(fill no)
			(layer "B.Fab")
		)
		(fp_text user "Author: Antmicro"
			(at -0.95 -4.169 90)
			(layer "B.Fab")
			(effects
				(font
					(size 0.7 0.7)
					(thickness 0.15)
				)
				(justify left bottom mirror)
			)
		)
		(fp_text user "${REFERENCE}"
			(at -0.95 -3.168 90)
			(layer "B.Fab")
			(effects
				(font
					(size 0.7 0.7)
					(thickness 0.15)
				)
				(justify left bottom mirror)
			)
		)
		(fp_text user "License: Apache-2.0"
			(at -0.95 -5.169 90)
			(layer "B.Fab")
			(effects
				(font
					(size 0.7 0.7)
					(thickness 0.15)
				)
				(justify left bottom mirror)
			)
		)
		(pad "1" smd roundrect
			(at -0.48 0 270)
			(size 0.59 0.64)
			(layers "B.Cu" "B.Mask" "B.Paste")
			(roundrect_rratio 0.25)
			(net 979 "/CSI/CSIA_I2C_VCC")
			(pintype "passive")
		)
		(pad "2" smd roundrect
			(at 0.48 0 270)
			(size 0.59 0.64)
			(layers "B.Cu" "B.Mask" "B.Paste")
			(roundrect_rratio 0.25)
			(net 986 "/CSI/SDA_CAM1")
			(pintype "passive")
		)
	)
	(footprint "antmicro-footprints:TP_SMD_0.75mm"
		(layer "B.Cu")
		(at 197.5 73.62 180)
		(property "Reference" "TP91"
			(at 0 0.6 0)
			(layer "B.SilkS")
			(effects
				(font
					(size 0.7 0.7)
					(thickness 0.15)
				)
				(justify left bottom mirror)
			)
		)
		(property "Value" "TP_0.75mm_SMD"
			(at 0 -1.2 0)
			(layer "B.Fab")
			(effects
				(font
					(size 0.7 0.7)
					(thickness 0.15)
				)
				(justify left bottom mirror)
			)
		)
		(property "Description" "SMT test point"
			(at 0 0 0)
			(layer "B.Fab")
			(hide yes)
			(effects
				(font
					(size 1.27 1.27)
					(thickness 0.15)
				)
				(justify mirror)
			)
		)
		(property "MPN" ""
			(at 0 0 0)
			(unlocked yes)
			(layer "B.Fab")
			(hide yes)
			(effects
				(font
					(size 1 1)
					(thickness 0.15)
				)
				(justify mirror)
			)
		)
		(property "Manufacturer" ""
			(at 0 0 0)
			(unlocked yes)
			(layer "B.Fab")
			(hide yes)
			(effects
				(font
					(size 1 1)
					(thickness 0.15)
				)
				(justify mirror)
			)
		)
		(property "Author" "Antmicro"
			(at 0 0 0)
			(unlocked yes)
			(layer "B.Fab")
			(hide yes)
			(effects
				(font
					(size 1 1)
					(thickness 0.15)
				)
				(justify mirror)
			)
		)
		(property "License" "Apache-2.0"
			(at 0 0 0)
			(unlocked yes)
			(layer "B.Fab")
			(hide yes)
			(effects
				(font
					(size 1 1)
					(thickness 0.15)
				)
				(justify mirror)
			)
		)
		(sheetname "/USB Debug, PD/")
		(sheetfile "usb_debug_pd.kicad_sch")
		(attr exclude_from_pos_files exclude_from_bom)
		(fp_circle
			(center 0 0)
			(end 0.475 0)
			(stroke
				(width 0.05)
				(type default)
			)
			(fill no)
			(layer "B.CrtYd")
		)
		(fp_text user "Author: Antmicro"
			(at -0.4 -3.901 0)
			(layer "B.Fab")
			(effects
				(font
					(size 0.7 0.7)
					(thickness 0.15)
				)
				(justify left bottom mirror)
			)
		)
		(fp_text user "License: Apache-2.0"
			(at -0.4 -5.101 0)
			(layer "B.Fab")
			(effects
				(font
					(size 0.7 0.7)
					(thickness 0.15)
				)
				(justify left bottom mirror)
			)
		)
		(fp_text user "${REFERENCE}"
			(at -0.4 -2.7 0)
			(layer "B.Fab")
			(effects
				(font
					(size 0.7 0.7)
					(thickness 0.15)
				)
				(justify left bottom mirror)
			)
		)
		(pad "1" smd circle
			(at 0 0 180)
			(size 0.75 0.75)
			(layers "B.Cu" "B.Mask")
			(net 946 "/USB Debug, PD/DEBUG_SDA")
			(pinfunction "1")
			(pintype "passive")
		)
	)
)
